(kicad_pcb
	(version 20260206)
	(generator "pcbnew")
	(generator_version "10.0")
	(general
		(thickness 1.6)
		(legacy_teardrops no)
	)
	(paper "A4")
	(title_block
		(title "Wiwynn_Tioga_Pass_MB.brd")
		(comment 1 "Tioga Pass / footprints 3729-3736 of 4770")
	)
	(layers
		(0 "F.Cu" signal "TOP")
		(4 "In1.Cu" signal "L2GND")
		(6 "In2.Cu" signal "L3")
		(8 "In3.Cu" signal "L4GND")
		(10 "In4.Cu" signal "L5")
		(12 "In5.Cu" signal "L6GND")
		(14 "In6.Cu" signal "L7VCC")
		(16 "In7.Cu" signal "L8VCC")
		(18 "In8.Cu" signal "L9GND")
		(20 "In9.Cu" signal "L10")
		(22 "In10.Cu" signal "L11GND")
		(24 "In11.Cu" signal "L12")
		(26 "In12.Cu" signal "L13GND")
		(2 "B.Cu" signal "BOTTOM")
		(9 "F.Adhes" user "F.Adhesive")
		(11 "B.Adhes" user "B.Adhesive")
		(13 "F.Paste" user "Package Geometry/Pastemask Top")
		(15 "B.Paste" user "Package Geometry/Pastemask Bottom")
		(5 "F.SilkS" user "Ref Des/Silkscreen Top")
		(7 "B.SilkS" user "Ref Des/Silkscreen Bottom")
		(1 "F.Mask" user "Board Geometry/Soldermask Top")
		(3 "B.Mask" user "Board Geometry/Soldermask Bottom")
		(17 "Dwgs.User" user "User.Drawings")
		(19 "Cmts.User" user "User.Comments")
		(21 "Eco1.User" user "User.Eco1")
		(23 "Eco2.User" user "User.Eco2")
		(25 "Edge.Cuts" user "Board Geometry/Outline")
		(27 "Margin" user)
		(31 "F.CrtYd" user "Package Geometry/Place Bound Top")
		(29 "B.CrtYd" user "Package Geometry/Place Bound Bottom")
		(35 "F.Fab" user "Ref Des/Assembly Top")
		(33 "B.Fab" user "Ref Des/Assembly Bottom")
	)
	(footprint ""
		(layer "B.Cu")
		(at 462.949544 -10.69848 -90)
		(property "Reference" "C2T36"
			(at 0 0 90)
			(layer "B.SilkS")
			(hide yes)
			(effects
				(font
					(size 1.27 1.27)
				)
				(justify mirror)
			)
		)
		(property "Value" ""
			(at 0 0 90)
			(layer "B.Fab")
			(effects
				(font
					(size 1.27 1.27)
				)
				(justify mirror)
			)
		)
		(duplicate_pad_numbers_are_jumpers no)
		(fp_rect
			(start -0.3048 0.9906)
			(end 0.3048 -0.1016)
			(stroke
				(width 0)
				(type default)
			)
			(fill no)
			(layer "B.CrtYd")
		)
		(fp_line
			(start -0.3048 0.9906)
			(end -0.3048 -0.1016)
			(stroke
				(width 0.1)
				(type default)
			)
			(layer "B.Fab")
		)
		(fp_line
			(start 0.3048 0.9906)
			(end -0.3048 0.9906)
			(stroke
				(width 0.1)
				(type default)
			)
			(layer "B.Fab")
		)
		(fp_line
			(start -0.3048 -0.1016)
			(end 0.3048 -0.1016)
			(stroke
				(width 0.1)
				(type default)
			)
			(layer "B.Fab")
		)
		(fp_line
			(start 0.3048 -0.1016)
			(end 0.3048 0.9906)
			(stroke
				(width 0.1)
				(type default)
			)
			(layer "B.Fab")
		)
		(pad "1" smd rect
			(at 0 0 90)
			(size 0.508 0.508)
			(layers "B.Cu" "B.Mask" "B.Paste")
			(net "P3V3_STBY")
		)
		(pad "2" smd rect
			(at 0 0.889 90)
			(size 0.508 0.508)
			(layers "B.Cu" "B.Mask" "B.Paste")
			(net "GND")
		)
		(zone
			(layer "B.Cu")
			(hatch none 0.5)
			(connect_pads
				(clearance 0)
			)
			(min_thickness 0.25)
			(keepout
				(tracks not_allowed)
				(vias allowed)
				(pads allowed)
				(copperpour not_allowed)
				(footprints allowed)
			)
			(placement
				(enabled no)
				(sheetname "")
			)
			(fill
				(thermal_gap 0.5)
				(thermal_bridge_width 0.5)
				(island_removal_mode 0)
			)
			(polygon
				(pts
					(xy 462.314544 -10.95248) (xy 462.314544 -10.44448) (xy 462.695544 -10.44448) (xy 462.695544 -10.95248)
				)
			)
		)
		(zone
			(layer "B.Cu")
			(hatch none 0.5)
			(connect_pads
				(clearance 0)
			)
			(min_thickness 0.25)
			(keepout
				(tracks allowed)
				(vias not_allowed)
				(pads allowed)
				(copperpour not_allowed)
				(footprints allowed)
			)
			(placement
				(enabled no)
				(sheetname "")
			)
			(fill
				(thermal_gap 0.5)
				(thermal_bridge_width 0.5)
				(island_removal_mode 0)
			)
			(polygon
				(pts
					(xy 462.314544 -10.95248) (xy 462.314544 -10.44448) (xy 462.695544 -10.44448) (xy 462.695544 -10.95248)
				)
			)
		)
	)
	(footprint ""
		(layer "B.Cu")
		(at 447.04 -116.49202)
		(property "Reference" "C1M18"
			(at 0 0 0)
			(layer "B.SilkS")
			(hide yes)
			(effects
				(font
					(size 1.27 1.27)
				)
				(justify mirror)
			)
		)
		(property "Value" ""
			(at 0 0 0)
			(layer "B.Fab")
			(effects
				(font
					(size 1.27 1.27)
				)
				(justify mirror)
			)
		)
		(duplicate_pad_numbers_are_jumpers no)
		(fp_rect
			(start -0.3048 0.9906)
			(end 0.3048 -0.1016)
			(stroke
				(width 0)
				(type default)
			)
			(fill no)
			(layer "B.CrtYd")
		)
		(fp_line
			(start -0.3048 -0.1016)
			(end 0.3048 -0.1016)
			(stroke
				(width 0.1)
				(type default)
			)
			(layer "B.Fab")
		)
		(fp_line
			(start -0.3048 0.9906)
			(end -0.3048 -0.1016)
			(stroke
				(width 0.1)
				(type default)
			)
			(layer "B.Fab")
		)
		(fp_line
			(start 0.3048 -0.1016)
			(end 0.3048 0.9906)
			(stroke
				(width 0.1)
				(type default)
			)
			(layer "B.Fab")
		)
		(fp_line
			(start 0.3048 0.9906)
			(end -0.3048 0.9906)
			(stroke
				(width 0.1)
				(type default)
			)
			(layer "B.Fab")
		)
		(pad "1" smd rect
			(at 0 0 180)
			(size 0.508 0.508)
			(layers "B.Cu" "B.Mask" "B.Paste")
			(net "P3E_CPU0_PE3_OCP_TXP<9>")
		)
		(pad "2" smd rect
			(at 0 0.889 180)
			(size 0.508 0.508)
			(layers "B.Cu" "B.Mask" "B.Paste")
			(net "P3E_OCP_CPU0_PE3_C_TXP<9>")
		)
		(zone
			(layer "B.Cu")
			(hatch none 0.5)
			(connect_pads
				(clearance 0)
			)
			(min_thickness 0.25)
			(keepout
				(tracks allowed)
				(vias not_allowed)
				(pads allowed)
				(copperpour not_allowed)
				(footprints allowed)
			)
			(placement
				(enabled no)
				(sheetname "")
			)
			(fill
				(thermal_gap 0.5)
				(thermal_bridge_width 0.5)
				(island_removal_mode 0)
			)
			(polygon
				(pts
					(xy 446.786 -115.85702) (xy 447.294 -115.85702) (xy 447.294 -116.23802) (xy 446.786 -116.23802)
				)
			)
		)
		(zone
			(layer "B.Cu")
			(hatch none 0.5)
			(connect_pads
				(clearance 0)
			)
			(min_thickness 0.25)
			(keepout
				(tracks not_allowed)
				(vias allowed)
				(pads allowed)
				(copperpour not_allowed)
				(footprints allowed)
			)
			(placement
				(enabled no)
				(sheetname "")
			)
			(fill
				(thermal_gap 0.5)
				(thermal_bridge_width 0.5)
				(island_removal_mode 0)
			)
			(polygon
				(pts
					(xy 446.786 -115.85702) (xy 447.294 -115.85702) (xy 447.294 -116.23802) (xy 446.786 -116.23802)
				)
			)
		)
	)
	(footprint ""
		(layer "B.Cu")
		(at 372.9482 -133.8072 -90)
		(property "Reference" "C3M24"
			(at 0 0 90)
			(layer "B.SilkS")
			(hide yes)
			(effects
				(font
					(size 1.27 1.27)
				)
				(justify mirror)
			)
		)
		(property "Value" ""
			(at 0 0 90)
			(layer "B.Fab")
			(effects
				(font
					(size 1.27 1.27)
				)
				(justify mirror)
			)
		)
		(duplicate_pad_numbers_are_jumpers no)
		(fp_rect
			(start 0.4953 1.6002)
			(end -0.4953 -0.2032)
			(stroke
				(width 0)
				(type default)
			)
			(fill no)
			(layer "B.CrtYd")
		)
		(fp_line
			(start -0.4953 1.6002)
			(end 0.4953 1.6002)
			(stroke
				(width 0.1)
				(type default)
			)
			(layer "B.Fab")
		)
		(fp_line
			(start 0.4953 1.6002)
			(end 0.4953 -0.2032)
			(stroke
				(width 0.1)
				(type default)
			)
			(layer "B.Fab")
		)
		(fp_line
			(start -0.4953 -0.2032)
			(end -0.4953 1.6002)
			(stroke
				(width 0.1)
				(type default)
			)
			(layer "B.Fab")
		)
		(fp_line
			(start 0.4953 -0.2032)
			(end -0.4953 -0.2032)
			(stroke
				(width 0.1)
				(type default)
			)
			(layer "B.Fab")
		)
		(pad "1" smd rect
			(at 0 0 90)
			(size 0.762 0.889)
			(layers "B.Cu" "B.Mask" "B.Paste")
			(net "P1V05_PCH_STBY_ISCLK_PLL")
		)
		(pad "2" smd rect
			(at 0 1.397 90)
			(size 0.762 0.889)
			(layers "B.Cu" "B.Mask" "B.Paste")
			(net "GND")
		)
		(zone
			(layer "B.Cu")
			(hatch none 0.5)
			(connect_pads
				(clearance 0)
			)
			(min_thickness 0.25)
			(keepout
				(tracks not_allowed)
				(vias allowed)
				(pads allowed)
				(copperpour not_allowed)
				(footprints allowed)
			)
			(placement
				(enabled no)
				(sheetname "")
			)
			(fill
				(thermal_gap 0.5)
				(thermal_bridge_width 0.5)
				(island_removal_mode 0)
			)
			(polygon
				(pts
					(xy 371.9957 -133.4262) (xy 372.5037 -133.4262) (xy 372.5037 -134.1882) (xy 371.9957 -134.1882)
				)
			)
		)
	)
	(footprint ""
		(layer "B.Cu")
		(at 420.923466 -45.536612 90)
		(property "Reference" "R25W96"
			(at 0.8382 -0.67818 90)
			(unlocked yes)
			(layer "B.SilkS")
			(effects
				(font
					(size 0.4064 0.254)
					(thickness 0.1524)
				)
				(justify left mirror)
			)
		)
		(property "Value" ""
			(at 0 0 90)
			(layer "B.Fab")
			(effects
				(font
					(size 1.27 1.27)
				)
				(justify mirror)
			)
		)
		(duplicate_pad_numbers_are_jumpers no)
		(fp_poly
			(pts
				(xy 0.2794 -0.1016) (xy -0.2794 -0.1016) (xy -0.2794 0.9906) (xy 0.2794 0.9906)
			)
			(stroke
				(width 0)
				(type default)
			)
			(fill no)
			(layer "B.CrtYd")
		)
		(fp_line
			(start 0.2794 -0.1016)
			(end 0.2794 0.9906)
			(stroke
				(width 0.1)
				(type default)
			)
			(layer "B.Fab")
		)
		(fp_line
			(start -0.2794 -0.1016)
			(end 0.2794 -0.1016)
			(stroke
				(width 0.1)
				(type default)
			)
			(layer "B.Fab")
		)
		(fp_line
			(start 0.2794 0.9906)
			(end -0.2794 0.9906)
			(stroke
				(width 0.1)
				(type default)
			)
			(layer "B.Fab")
		)
		(fp_line
			(start -0.2794 0.9906)
			(end -0.2794 -0.1016)
			(stroke
				(width 0.1)
				(type default)
			)
			(layer "B.Fab")
		)
		(pad "1" smd rect
			(at 0 0 270)
			(size 0.508 0.508)
			(layers "B.Cu" "B.Mask" "B.Paste")
			(net "P3V3_STBY")
		)
		(pad "2" smd rect
			(at 0 0.889 270)
			(size 0.508 0.508)
			(layers "B.Cu" "B.Mask" "B.Paste")
			(net "SPI_BMC_BT_DO")
		)
		(zone
			(layer "B.Cu")
			(hatch none 0.5)
			(connect_pads
				(clearance 0)
			)
			(min_thickness 0.25)
			(keepout
				(tracks allowed)
				(vias not_allowed)
				(pads allowed)
				(copperpour not_allowed)
				(footprints allowed)
			)
			(placement
				(enabled no)
				(sheetname "")
			)
			(fill
				(thermal_gap 0.5)
				(thermal_bridge_width 0.5)
				(island_removal_mode 0)
			)
			(polygon
				(pts
					(xy 421.177466 -45.790612) (xy 421.177466 -45.282612) (xy 421.558466 -45.282612) (xy 421.558466 -45.790612)
				)
			)
		)
		(zone
			(layer "B.Cu")
			(hatch none 0.5)
			(connect_pads
				(clearance 0)
			)
			(min_thickness 0.25)
			(keepout
				(tracks not_allowed)
				(vias allowed)
				(pads allowed)
				(copperpour not_allowed)
				(footprints allowed)
			)
			(placement
				(enabled no)
				(sheetname "")
			)
			(fill
				(thermal_gap 0.5)
				(thermal_bridge_width 0.5)
				(island_removal_mode 0)
			)
			(polygon
				(pts
					(xy 421.558466 -45.790612) (xy 421.558466 -45.282612) (xy 421.177466 -45.282612) (xy 421.177466 -45.790612)
				)
			)
		)
	)
	(footprint ""
		(layer "B.Cu")
		(at 400.829526 -149.663912 -90)
		(property "Reference" "R2L17"
			(at 0.8382 -0.84963 270)
			(unlocked yes)
			(layer "B.SilkS")
			(effects
				(font
					(size 0.7874 0.5842)
					(thickness 0.1524)
				)
				(justify left mirror)
			)
		)
		(property "Value" ""
			(at 0 0 90)
			(layer "B.Fab")
			(effects
				(font
					(size 1.27 1.27)
				)
				(justify mirror)
			)
		)
		(duplicate_pad_numbers_are_jumpers no)
		(fp_poly
			(pts
				(xy 0.2794 -0.1016) (xy -0.2794 -0.1016) (xy -0.2794 0.9906) (xy 0.2794 0.9906)
			)
			(stroke
				(width 0)
				(type default)
			)
			(fill no)
			(layer "B.CrtYd")
		)
		(fp_line
			(start -0.2794 0.9906)
			(end -0.2794 -0.1016)
			(stroke
				(width 0.1)
				(type default)
			)
			(layer "B.Fab")
		)
		(fp_line
			(start 0.2794 0.9906)
			(end -0.2794 0.9906)
			(stroke
				(width 0.1)
				(type default)
			)
			(layer "B.Fab")
		)
		(fp_line
			(start -0.2794 -0.1016)
			(end 0.2794 -0.1016)
			(stroke
				(width 0.1)
				(type default)
			)
			(layer "B.Fab")
		)
		(fp_line
			(start 0.2794 -0.1016)
			(end 0.2794 0.9906)
			(stroke
				(width 0.1)
				(type default)
			)
			(layer "B.Fab")
		)
		(pad "1" smd rect
			(at 0 0 90)
			(size 0.508 0.508)
			(layers "B.Cu" "B.Mask" "B.Paste")
			(net "PWRGD_P1V8_PCH_STBY")
		)
		(pad "2" smd rect
			(at 0 0.889 90)
			(size 0.508 0.508)
			(layers "B.Cu" "B.Mask" "B.Paste")
			(net "VR_PVNN_PCH_VREN")
		)
		(zone
			(layer "B.Cu")
			(hatch none 0.5)
			(connect_pads
				(clearance 0)
			)
			(min_thickness 0.25)
			(keepout
				(tracks not_allowed)
				(vias allowed)
				(pads allowed)
				(copperpour not_allowed)
				(footprints allowed)
			)
			(placement
				(enabled no)
				(sheetname "")
			)
			(fill
				(thermal_gap 0.5)
				(thermal_bridge_width 0.5)
				(island_removal_mode 0)
			)
			(polygon
				(pts
					(xy 400.194526 -149.409912) (xy 400.194526 -149.917912) (xy 400.575526 -149.917912) (xy 400.575526 -149.409912)
				)
			)
		)
		(zone
			(layer "B.Cu")
			(hatch none 0.5)
			(connect_pads
				(clearance 0)
			)
			(min_thickness 0.25)
			(keepout
				(tracks allowed)
				(vias not_allowed)
				(pads allowed)
				(copperpour not_allowed)
				(footprints allowed)
			)
			(placement
				(enabled no)
				(sheetname "")
			)
			(fill
				(thermal_gap 0.5)
				(thermal_bridge_width 0.5)
				(island_removal_mode 0)
			)
			(polygon
				(pts
					(xy 400.575526 -149.409912) (xy 400.575526 -149.917912) (xy 400.194526 -149.917912) (xy 400.194526 -149.409912)
				)
			)
		)
	)
	(footprint ""
		(layer "B.Cu")
		(at 474.650816 -145.470372 180)
		(property "Reference" "R6W12"
			(at 0.8382 -0.67818 180)
			(unlocked yes)
			(layer "B.SilkS")
			(effects
				(font
					(size 0.4064 0.254)
					(thickness 0.1524)
				)
				(justify left mirror)
			)
		)
		(property "Value" ""
			(at 0 0 0)
			(layer "B.Fab")
			(effects
				(font
					(size 1.27 1.27)
				)
				(justify mirror)
			)
		)
		(duplicate_pad_numbers_are_jumpers no)
		(fp_poly
			(pts
				(xy 0.2794 -0.1016) (xy -0.2794 -0.1016) (xy -0.2794 0.9906) (xy 0.2794 0.9906)
			)
			(stroke
				(width 0)
				(type default)
			)
			(fill no)
			(layer "B.CrtYd")
		)
		(fp_line
			(start 0.2794 0.9906)
			(end -0.2794 0.9906)
			(stroke
				(width 0.1)
				(type default)
			)
			(layer "B.Fab")
		)
		(fp_line
			(start 0.2794 -0.1016)
			(end 0.2794 0.9906)
			(stroke
				(width 0.1)
				(type default)
			)
			(layer "B.Fab")
		)
		(fp_line
			(start -0.2794 0.9906)
			(end -0.2794 -0.1016)
			(stroke
				(width 0.1)
				(type default)
			)
			(layer "B.Fab")
		)
		(fp_line
			(start -0.2794 -0.1016)
			(end 0.2794 -0.1016)
			(stroke
				(width 0.1)
				(type default)
			)
			(layer "B.Fab")
		)
		(pad "1" smd rect
			(at 0 0)
			(size 0.508 0.508)
			(layers "B.Cu" "B.Mask" "B.Paste")
			(net "SMB_DEBUG_STBY_LVC3_SDA")
		)
		(pad "2" smd rect
			(at 0 0.889)
			(size 0.508 0.508)
			(layers "B.Cu" "B.Mask" "B.Paste")
			(net "P3V3_STBY")
		)
		(zone
			(layer "B.Cu")
			(hatch none 0.5)
			(connect_pads
				(clearance 0)
			)
			(min_thickness 0.25)
			(keepout
				(tracks not_allowed)
				(vias allowed)
				(pads allowed)
				(copperpour not_allowed)
				(footprints allowed)
			)
			(placement
				(enabled no)
				(sheetname "")
			)
			(fill
				(thermal_gap 0.5)
				(thermal_bridge_width 0.5)
				(island_removal_mode 0)
			)
			(polygon
				(pts
					(xy 474.396816 -146.105372) (xy 474.904816 -146.105372) (xy 474.904816 -145.724372) (xy 474.396816 -145.724372)
				)
			)
		)
		(zone
			(layer "B.Cu")
			(hatch none 0.5)
			(connect_pads
				(clearance 0)
			)
			(min_thickness 0.25)
			(keepout
				(tracks allowed)
				(vias not_allowed)
				(pads allowed)
				(copperpour not_allowed)
				(footprints allowed)
			)
			(placement
				(enabled no)
				(sheetname "")
			)
			(fill
				(thermal_gap 0.5)
				(thermal_bridge_width 0.5)
				(island_removal_mode 0)
			)
			(polygon
				(pts
					(xy 474.396816 -145.724372) (xy 474.904816 -145.724372) (xy 474.904816 -146.105372) (xy 474.396816 -146.105372)
				)
			)
		)
	)
	(footprint ""
		(layer "B.Cu")
		(at 371.362986 -47.798482 180)
		(property "Reference" "R2T69"
			(at 0 0 0)
			(layer "B.SilkS")
			(hide yes)
			(effects
				(font
					(size 1.27 1.27)
				)
				(justify mirror)
			)
		)
		(property "Value" ""
			(at 0 0 0)
			(layer "B.Fab")
			(effects
				(font
					(size 1.27 1.27)
				)
				(justify mirror)
			)
		)
		(duplicate_pad_numbers_are_jumpers no)
		(fp_poly
			(pts
				(xy 0.2794 -0.1016) (xy -0.2794 -0.1016) (xy -0.2794 0.9906) (xy 0.2794 0.9906)
			)
			(stroke
				(width 0)
				(type default)
			)
			(fill no)
			(layer "B.CrtYd")
		)
		(fp_line
			(start 0.2794 0.9906)
			(end -0.2794 0.9906)
			(stroke
				(width 0.1)
				(type default)
			)
			(layer "B.Fab")
		)
		(fp_line
			(start 0.2794 -0.1016)
			(end 0.2794 0.9906)
			(stroke
				(width 0.1)
				(type default)
			)
			(layer "B.Fab")
		)
		(fp_line
			(start -0.2794 0.9906)
			(end -0.2794 -0.1016)
			(stroke
				(width 0.1)
				(type default)
			)
			(layer "B.Fab")
		)
		(fp_line
			(start -0.2794 -0.1016)
			(end 0.2794 -0.1016)
			(stroke
				(width 0.1)
				(type default)
			)
			(layer "B.Fab")
		)
		(pad "1" smd rect
			(at 0 0)
			(size 0.508 0.508)
			(layers "B.Cu" "B.Mask" "B.Paste")
			(net "H_CPU1_PROCHOT_G_N")
		)
		(pad "2" smd rect
			(at 0 0.889)
			(size 0.508 0.508)
			(layers "B.Cu" "B.Mask" "B.Paste")
			(net "H_CPU1_PROCHOT_G_PCH_N")
		)
		(zone
			(layer "B.Cu")
			(hatch none 0.5)
			(connect_pads
				(clearance 0)
			)
			(min_thickness 0.25)
			(keepout
				(tracks not_allowed)
				(vias allowed)
				(pads allowed)
				(copperpour not_allowed)
				(footprints allowed)
			)
			(placement
				(enabled no)
				(sheetname "")
			)
			(fill
				(thermal_gap 0.5)
				(thermal_bridge_width 0.5)
				(island_removal_mode 0)
			)
			(polygon
				(pts
					(xy 371.108986 -48.433482) (xy 371.616986 -48.433482) (xy 371.616986 -48.052482) (xy 371.108986 -48.052482)
				)
			)
		)
		(zone
			(layer "B.Cu")
			(hatch none 0.5)
			(connect_pads
				(clearance 0)
			)
			(min_thickness 0.25)
			(keepout
				(tracks allowed)
				(vias not_allowed)
				(pads allowed)
				(copperpour not_allowed)
				(footprints allowed)
			)
			(placement
				(enabled no)
				(sheetname "")
			)
			(fill
				(thermal_gap 0.5)
				(thermal_bridge_width 0.5)
				(island_removal_mode 0)
			)
			(polygon
				(pts
					(xy 371.108986 -48.052482) (xy 371.616986 -48.052482) (xy 371.616986 -48.433482) (xy 371.108986 -48.433482)
				)
			)
		)
	)
	(footprint ""
		(layer "B.Cu")
		(at 101.3968 -149.8092 90)
		(property "Reference" "C5G102"
			(at -1.14681 0.76708 180)
			(unlocked yes)
			(layer "B.SilkS")
			(effects
				(font
					(size 0.7874 0.5842)
					(thickness 0.1524)
				)
				(justify mirror)
			)
		)
		(property "Value" ""
			(at 0 0 90)
			(layer "B.Fab")
			(effects
				(font
					(size 1.27 1.27)
				)
				(justify mirror)
			)
		)
		(duplicate_pad_numbers_are_jumpers no)
		(fp_rect
			(start -0.4953 -0.2032)
			(end 0.4953 1.6002)
			(stroke
				(width 0)
				(type default)
			)
			(fill no)
			(layer "B.CrtYd")
		)
		(fp_line
			(start 0.4953 -0.2032)
			(end -0.4953 -0.2032)
			(stroke
				(width 0.1)
				(type default)
			)
			(layer "B.Fab")
		)
		(fp_line
			(start -0.4953 -0.2032)
			(end -0.4953 1.6002)
			(stroke
				(width 0.1)
				(type default)
			)
			(layer "B.Fab")
		)
		(fp_line
			(start 0.4953 1.6002)
			(end 0.4953 -0.2032)
			(stroke
				(width 0.1)
				(type default)
			)
			(layer "B.Fab")
		)
		(fp_line
			(start -0.4953 1.6002)
			(end 0.4953 1.6002)
			(stroke
				(width 0.1)
				(type default)
			)
			(layer "B.Fab")
		)
		(pad "1" smd rect
			(at 0 0 270)
			(size 0.762 0.889)
			(layers "B.Cu" "B.Mask" "B.Paste")
			(net "PVDDQ_KLM")
		)
		(pad "2" smd rect
			(at 0 1.397 270)
			(size 0.762 0.889)
			(layers "B.Cu" "B.Mask" "B.Paste")
			(net "GND")
		)
		(zone
			(layer "B.Cu")
			(hatch none 0.5)
			(connect_pads
				(clearance 0)
			)
			(min_thickness 0.25)
			(keepout
				(tracks not_allowed)
				(vias allowed)
				(pads allowed)
				(copperpour not_allowed)
				(footprints allowed)
			)
			(placement
				(enabled no)
				(sheetname "")
			)
			(fill
				(thermal_gap 0.5)
				(thermal_bridge_width 0.5)
				(island_removal_mode 0)
			)
			(polygon
				(pts
					(xy 101.8413 -149.4282) (xy 102.3493 -149.4282) (xy 102.3493 -150.1902) (xy 101.8413 -150.1902)
				)
			)
		)
	)
)
